(kicad_pcb
	(version 20260206)
	(generator "pcbnew")
	(generator_version "10.0")
	(general
		(thickness 1.6)
		(legacy_teardrops no)
	)
	(paper "A4")
	(title_block
		(title "04192023_DAF0TMB3IC0_F0TG_MB_C_brd_V02_OCP.brd")
		(comment 1 "Grand Teton / footprints 2915-2920 of 8354")
	)
	(layers
		(0 "F.Cu" signal "TOP")
		(4 "In1.Cu" signal "GND")
		(6 "In2.Cu" signal "IN1")
		(8 "In3.Cu" signal "GND1")
		(10 "In4.Cu" signal "IN2")
		(12 "In5.Cu" signal "GND2")
		(14 "In6.Cu" signal "IN3")
		(16 "In7.Cu" signal "GND3")
		(18 "In8.Cu" signal "VCC")
		(20 "In9.Cu" signal "VCC1")
		(22 "In10.Cu" signal "GND4")
		(24 "In11.Cu" signal "IN4")
		(26 "In12.Cu" signal "GND5")
		(28 "In13.Cu" signal "IN5")
		(30 "In14.Cu" signal "GND6")
		(32 "In15.Cu" signal "IN6")
		(34 "In16.Cu" signal "GND7")
		(2 "B.Cu" signal "BOTTOM")
		(9 "F.Adhes" user "F.Adhesive")
		(11 "B.Adhes" user "B.Adhesive")
		(13 "F.Paste" user "Package Geometry/Pastemask Top")
		(15 "B.Paste" user "Package Geometry/Pastemask Bottom")
		(5 "F.SilkS" user "Ref Des/Silkscreen Top")
		(7 "B.SilkS" user "Ref Des/Silkscreen Bottom")
		(1 "F.Mask" user "Board Geometry/Soldermask Top")
		(3 "B.Mask" user "Board Geometry/Soldermask Bottom")
		(17 "Dwgs.User" user "User.Drawings")
		(19 "Cmts.User" user "User.Comments")
		(21 "Eco1.User" user "User.Eco1")
		(23 "Eco2.User" user "User.Eco2")
		(25 "Edge.Cuts" user "Board Geometry/Outline")
		(27 "Margin" user)
		(31 "F.CrtYd" user "Package Geometry/Place Bound Top")
		(29 "B.CrtYd" user "Package Geometry/Place Bound Bottom")
		(35 "F.Fab" user "Ref Des/Assembly Top")
		(33 "B.Fab" user "Ref Des/Assembly Bottom")
	)
	(footprint ""
		(layer "F.Cu")
		(at 439.029602 -423.66311)
		(property "Reference" "PR6805"
			(at 0 0 0)
			(layer "F.SilkS")
			(hide yes)
			(effects
				(font
					(size 1.27 1.27)
				)
			)
		)
		(property "Value" ""
			(at 0 0 0)
			(layer "F.Fab")
			(effects
				(font
					(size 1.27 1.27)
				)
			)
		)
		(duplicate_pad_numbers_are_jumpers no)
		(fp_line
			(start -0.7874 -0.4064)
			(end 0.7874 -0.4064)
			(stroke
				(width 0.1524)
				(type default)
			)
			(layer "F.SilkS")
		)
		(fp_line
			(start -0.7874 0.4064)
			(end -0.7874 -0.4064)
			(stroke
				(width 0.1524)
				(type default)
			)
			(layer "F.SilkS")
		)
		(fp_line
			(start 0.7874 -0.4064)
			(end 0.7874 0.4064)
			(stroke
				(width 0.1524)
				(type default)
			)
			(layer "F.SilkS")
		)
		(fp_line
			(start 0.7874 0.4064)
			(end -0.7874 0.4064)
			(stroke
				(width 0.1524)
				(type default)
			)
			(layer "F.SilkS")
		)
		(fp_line
			(start -0.67945 -0.305054)
			(end -0.12065 -0.305054)
			(stroke
				(width 0.1)
				(type default)
			)
			(layer "F.Fab")
		)
		(fp_line
			(start -0.67945 0.3048)
			(end -0.67945 -0.305054)
			(stroke
				(width 0.1)
				(type default)
			)
			(layer "F.Fab")
		)
		(fp_line
			(start -0.12065 -0.305054)
			(end -0.12065 -0.2794)
			(stroke
				(width 0.1)
				(type default)
			)
			(layer "F.Fab")
		)
		(fp_line
			(start -0.12065 -0.2794)
			(end 0.12065 -0.2794)
			(stroke
				(width 0.1)
				(type default)
			)
			(layer "F.Fab")
		)
		(fp_line
			(start -0.12065 0.2794)
			(end -0.12065 0.3048)
			(stroke
				(width 0.1)
				(type default)
			)
			(layer "F.Fab")
		)
		(fp_line
			(start -0.12065 0.3048)
			(end -0.67945 0.3048)
			(stroke
				(width 0.1)
				(type default)
			)
			(layer "F.Fab")
		)
		(fp_line
			(start 0.120396 0.2794)
			(end -0.12065 0.2794)
			(stroke
				(width 0.1)
				(type default)
			)
			(layer "F.Fab")
		)
		(fp_line
			(start 0.120396 0.3048)
			(end 0.120396 0.2794)
			(stroke
				(width 0.1)
				(type default)
			)
			(layer "F.Fab")
		)
		(fp_line
			(start 0.12065 -0.3048)
			(end 0.67945 -0.3048)
			(stroke
				(width 0.1)
				(type default)
			)
			(layer "F.Fab")
		)
		(fp_line
			(start 0.12065 -0.2794)
			(end 0.12065 -0.3048)
			(stroke
				(width 0.1)
				(type default)
			)
			(layer "F.Fab")
		)
		(fp_line
			(start 0.67945 -0.3048)
			(end 0.67945 0.3048)
			(stroke
				(width 0.1)
				(type default)
			)
			(layer "F.Fab")
		)
		(fp_line
			(start 0.67945 0.3048)
			(end 0.120396 0.3048)
			(stroke
				(width 0.1)
				(type default)
			)
			(layer "F.Fab")
		)
		(pad "1" smd circle
			(at -0.40005 0)
			(size 0 0)
			(layers "F.Cu" "F.Mask" "F.Paste")
			(net "P3V3_AUX")
		)
		(pad "2" smd circle
			(at 0.40005 0)
			(size 0 0)
			(layers "F.Cu" "F.Mask" "F.Paste")
			(net "P0V9_RETIMER_CPU0_SVID_CLK")
		)
	)
	(footprint ""
		(layer "F.Cu")
		(at 429.278796 -393.9032 90)
		(property "Reference" "C665"
			(at 0 0 90)
			(layer "F.SilkS")
			(hide yes)
			(effects
				(font
					(size 1.27 1.27)
				)
			)
		)
		(property "Value" ""
			(at 0 0 90)
			(layer "F.Fab")
			(effects
				(font
					(size 1.27 1.27)
				)
			)
		)
		(duplicate_pad_numbers_are_jumpers no)
		(fp_line
			(start 1.524 -0.762)
			(end 1.524 0.762)
			(stroke
				(width 0.1524)
				(type default)
			)
			(layer "F.SilkS")
		)
		(fp_line
			(start -1.524 -0.762)
			(end 1.524 -0.762)
			(stroke
				(width 0.1524)
				(type default)
			)
			(layer "F.SilkS")
		)
		(fp_line
			(start 1.524 0.762)
			(end -1.524 0.762)
			(stroke
				(width 0.1524)
				(type default)
			)
			(layer "F.SilkS")
		)
		(fp_line
			(start -1.524 0.762)
			(end -1.524 -0.762)
			(stroke
				(width 0.1524)
				(type default)
			)
			(layer "F.SilkS")
		)
		(fp_line
			(start 1.1049 -0.724916)
			(end -1.1049 -0.724916)
			(stroke
				(width 0.1)
				(type default)
			)
			(layer "F.Fab")
		)
		(fp_line
			(start -1.1049 -0.724916)
			(end -1.1049 0.724916)
			(stroke
				(width 0.1)
				(type default)
			)
			(layer "F.Fab")
		)
		(fp_line
			(start 1.1049 0.724916)
			(end 1.1049 -0.724916)
			(stroke
				(width 0.1)
				(type default)
			)
			(layer "F.Fab")
		)
		(fp_line
			(start -1.1049 0.724916)
			(end 1.1049 0.724916)
			(stroke
				(width 0.1)
				(type default)
			)
			(layer "F.Fab")
		)
		(pad "1" smd rect
			(at -0.889 0 270)
			(size 1.016 1.27)
			(layers "F.Cu" "F.Mask" "F.Paste")
			(net "P1V8_CPU0_RT_1D")
		)
		(pad "2" smd rect
			(at 0.889 0 270)
			(size 1.016 1.27)
			(layers "F.Cu" "F.Mask" "F.Paste")
			(net "GND")
		)
	)
	(footprint ""
		(layer "F.Cu")
		(at 215.4301 -404.020782)
		(property "Reference" "PC2183"
			(at 0 0 0)
			(layer "F.SilkS")
			(hide yes)
			(effects
				(font
					(size 1.27 1.27)
				)
			)
		)
		(property "Value" ""
			(at 0 0 0)
			(layer "F.Fab")
			(effects
				(font
					(size 1.27 1.27)
				)
			)
		)
		(duplicate_pad_numbers_are_jumpers no)
		(fp_line
			(start -0.7874 -0.4064)
			(end 0.7874 -0.4064)
			(stroke
				(width 0.1524)
				(type default)
			)
			(layer "F.SilkS")
		)
		(fp_line
			(start -0.7874 0.4064)
			(end -0.7874 -0.4064)
			(stroke
				(width 0.1524)
				(type default)
			)
			(layer "F.SilkS")
		)
		(fp_line
			(start 0.7874 -0.4064)
			(end 0.7874 0.4064)
			(stroke
				(width 0.1524)
				(type default)
			)
			(layer "F.SilkS")
		)
		(fp_line
			(start 0.7874 0.4064)
			(end -0.7874 0.4064)
			(stroke
				(width 0.1524)
				(type default)
			)
			(layer "F.SilkS")
		)
		(fp_line
			(start -0.67945 -0.305054)
			(end -0.12065 -0.305054)
			(stroke
				(width 0.1)
				(type default)
			)
			(layer "F.Fab")
		)
		(fp_line
			(start -0.67945 0.3048)
			(end -0.67945 -0.305054)
			(stroke
				(width 0.1)
				(type default)
			)
			(layer "F.Fab")
		)
		(fp_line
			(start -0.12065 -0.305054)
			(end -0.12065 -0.2794)
			(stroke
				(width 0.1)
				(type default)
			)
			(layer "F.Fab")
		)
		(fp_line
			(start -0.12065 -0.2794)
			(end 0.12065 -0.2794)
			(stroke
				(width 0.1)
				(type default)
			)
			(layer "F.Fab")
		)
		(fp_line
			(start -0.12065 0.2794)
			(end -0.12065 0.3048)
			(stroke
				(width 0.1)
				(type default)
			)
			(layer "F.Fab")
		)
		(fp_line
			(start -0.12065 0.3048)
			(end -0.67945 0.3048)
			(stroke
				(width 0.1)
				(type default)
			)
			(layer "F.Fab")
		)
		(fp_line
			(start 0.120396 0.2794)
			(end -0.12065 0.2794)
			(stroke
				(width 0.1)
				(type default)
			)
			(layer "F.Fab")
		)
		(fp_line
			(start 0.120396 0.3048)
			(end 0.120396 0.2794)
			(stroke
				(width 0.1)
				(type default)
			)
			(layer "F.Fab")
		)
		(fp_line
			(start 0.12065 -0.3048)
			(end 0.67945 -0.3048)
			(stroke
				(width 0.1)
				(type default)
			)
			(layer "F.Fab")
		)
		(fp_line
			(start 0.12065 -0.2794)
			(end 0.12065 -0.3048)
			(stroke
				(width 0.1)
				(type default)
			)
			(layer "F.Fab")
		)
		(fp_line
			(start 0.67945 -0.3048)
			(end 0.67945 0.3048)
			(stroke
				(width 0.1)
				(type default)
			)
			(layer "F.Fab")
		)
		(fp_line
			(start 0.67945 0.3048)
			(end 0.120396 0.3048)
			(stroke
				(width 0.1)
				(type default)
			)
			(layer "F.Fab")
		)
		(pad "1" smd circle
			(at -0.40005 0)
			(size 0 0)
			(layers "F.Cu" "F.Mask" "F.Paste")
			(net "HSC_ON")
		)
		(pad "2" smd circle
			(at 0.40005 0)
			(size 0 0)
			(layers "F.Cu" "F.Mask" "F.Paste")
			(net "AGND_HSC")
		)
	)
	(footprint ""
		(layer "F.Cu")
		(at 363.318044 -418.360098 180)
		(property "Reference" "R9004"
			(at 0 0 180)
			(layer "F.SilkS")
			(hide yes)
			(effects
				(font
					(size 1.27 1.27)
				)
			)
		)
		(property "Value" ""
			(at 0 0 180)
			(layer "F.Fab")
			(effects
				(font
					(size 1.27 1.27)
				)
			)
		)
		(duplicate_pad_numbers_are_jumpers no)
		(fp_line
			(start 0.7874 0.4064)
			(end -0.7874 0.4064)
			(stroke
				(width 0.1524)
				(type default)
			)
			(layer "F.SilkS")
		)
		(fp_line
			(start 0.7874 -0.4064)
			(end 0.7874 0.4064)
			(stroke
				(width 0.1524)
				(type default)
			)
			(layer "F.SilkS")
		)
		(fp_line
			(start -0.7874 0.4064)
			(end -0.7874 -0.4064)
			(stroke
				(width 0.1524)
				(type default)
			)
			(layer "F.SilkS")
		)
		(fp_line
			(start -0.7874 -0.4064)
			(end 0.7874 -0.4064)
			(stroke
				(width 0.1524)
				(type default)
			)
			(layer "F.SilkS")
		)
		(fp_line
			(start 0.67945 0.3048)
			(end 0.120396 0.3048)
			(stroke
				(width 0.1)
				(type default)
			)
			(layer "F.Fab")
		)
		(fp_line
			(start 0.67945 -0.3048)
			(end 0.67945 0.3048)
			(stroke
				(width 0.1)
				(type default)
			)
			(layer "F.Fab")
		)
		(fp_line
			(start 0.12065 -0.2794)
			(end 0.12065 -0.3048)
			(stroke
				(width 0.1)
				(type default)
			)
			(layer "F.Fab")
		)
		(fp_line
			(start 0.12065 -0.3048)
			(end 0.67945 -0.3048)
			(stroke
				(width 0.1)
				(type default)
			)
			(layer "F.Fab")
		)
		(fp_line
			(start 0.120396 0.3048)
			(end 0.120396 0.2794)
			(stroke
				(width 0.1)
				(type default)
			)
			(layer "F.Fab")
		)
		(fp_line
			(start 0.120396 0.2794)
			(end -0.12065 0.2794)
			(stroke
				(width 0.1)
				(type default)
			)
			(layer "F.Fab")
		)
		(fp_line
			(start -0.12065 0.3048)
			(end -0.67945 0.3048)
			(stroke
				(width 0.1)
				(type default)
			)
			(layer "F.Fab")
		)
		(fp_line
			(start -0.12065 0.2794)
			(end -0.12065 0.3048)
			(stroke
				(width 0.1)
				(type default)
			)
			(layer "F.Fab")
		)
		(fp_line
			(start -0.12065 -0.2794)
			(end 0.12065 -0.2794)
			(stroke
				(width 0.1)
				(type default)
			)
			(layer "F.Fab")
		)
		(fp_line
			(start -0.12065 -0.305054)
			(end -0.12065 -0.2794)
			(stroke
				(width 0.1)
				(type default)
			)
			(layer "F.Fab")
		)
		(fp_line
			(start -0.67945 0.3048)
			(end -0.67945 -0.305054)
			(stroke
				(width 0.1)
				(type default)
			)
			(layer "F.Fab")
		)
		(fp_line
			(start -0.67945 -0.305054)
			(end -0.12065 -0.305054)
			(stroke
				(width 0.1)
				(type default)
			)
			(layer "F.Fab")
		)
		(pad "1" smd circle
			(at -0.40005 0 180)
			(size 0 0)
			(layers "F.Cu" "F.Mask" "F.Paste")
			(net "P3V3_AUX")
		)
		(pad "2" smd circle
			(at 0.40005 0 180)
			(size 0 0)
			(layers "F.Cu" "F.Mask" "F.Paste")
			(net "PRSNT_CABLE_SWB_B1")
		)
	)
	(footprint ""
		(layer "F.Cu")
		(at 63.877698 -26.99004 -90)
		(property "Reference" "PR3854"
			(at 0 0 270)
			(layer "F.SilkS")
			(hide yes)
			(effects
				(font
					(size 1.27 1.27)
				)
			)
		)
		(property "Value" ""
			(at 0 0 270)
			(layer "F.Fab")
			(effects
				(font
					(size 1.27 1.27)
				)
			)
		)
		(duplicate_pad_numbers_are_jumpers no)
		(fp_line
			(start -0.7874 0.4064)
			(end -0.7874 -0.4064)
			(stroke
				(width 0.1524)
				(type default)
			)
			(layer "F.SilkS")
		)
		(fp_line
			(start 0.7874 0.4064)
			(end -0.7874 0.4064)
			(stroke
				(width 0.1524)
				(type default)
			)
			(layer "F.SilkS")
		)
		(fp_line
			(start -0.7874 -0.4064)
			(end 0.7874 -0.4064)
			(stroke
				(width 0.1524)
				(type default)
			)
			(layer "F.SilkS")
		)
		(fp_line
			(start 0.7874 -0.4064)
			(end 0.7874 0.4064)
			(stroke
				(width 0.1524)
				(type default)
			)
			(layer "F.SilkS")
		)
		(fp_line
			(start -0.67945 0.3048)
			(end -0.67945 -0.305054)
			(stroke
				(width 0.1)
				(type default)
			)
			(layer "F.Fab")
		)
		(fp_line
			(start -0.12065 0.3048)
			(end -0.67945 0.3048)
			(stroke
				(width 0.1)
				(type default)
			)
			(layer "F.Fab")
		)
		(fp_line
			(start 0.120396 0.3048)
			(end 0.120396 0.2794)
			(stroke
				(width 0.1)
				(type default)
			)
			(layer "F.Fab")
		)
		(fp_line
			(start 0.67945 0.3048)
			(end 0.120396 0.3048)
			(stroke
				(width 0.1)
				(type default)
			)
			(layer "F.Fab")
		)
		(fp_line
			(start -0.12065 0.2794)
			(end -0.12065 0.3048)
			(stroke
				(width 0.1)
				(type default)
			)
			(layer "F.Fab")
		)
		(fp_line
			(start 0.120396 0.2794)
			(end -0.12065 0.2794)
			(stroke
				(width 0.1)
				(type default)
			)
			(layer "F.Fab")
		)
		(fp_line
			(start -0.12065 -0.2794)
			(end 0.12065 -0.2794)
			(stroke
				(width 0.1)
				(type default)
			)
			(layer "F.Fab")
		)
		(fp_line
			(start 0.12065 -0.2794)
			(end 0.12065 -0.3048)
			(stroke
				(width 0.1)
				(type default)
			)
			(layer "F.Fab")
		)
		(fp_line
			(start 0.12065 -0.3048)
			(end 0.67945 -0.3048)
			(stroke
				(width 0.1)
				(type default)
			)
			(layer "F.Fab")
		)
		(fp_line
			(start 0.67945 -0.3048)
			(end 0.67945 0.3048)
			(stroke
				(width 0.1)
				(type default)
			)
			(layer "F.Fab")
		)
		(fp_line
			(start -0.67945 -0.305054)
			(end -0.12065 -0.305054)
			(stroke
				(width 0.1)
				(type default)
			)
			(layer "F.Fab")
		)
		(fp_line
			(start -0.12065 -0.305054)
			(end -0.12065 -0.2794)
			(stroke
				(width 0.1)
				(type default)
			)
			(layer "F.Fab")
		)
		(pad "1" smd circle
			(at -0.40005 0 270)
			(size 0 0)
			(layers "F.Cu" "F.Mask" "F.Paste")
			(net "P12V_OCP_OV_FB_2")
		)
		(pad "2" smd circle
			(at 0.40005 0 270)
			(size 0 0)
			(layers "F.Cu" "F.Mask" "F.Paste")
			(net "GND")
		)
	)
	(footprint ""
		(layer "F.Cu")
		(at 261.62 -143.764 180)
		(property "Reference" "R1531"
			(at 0 0 180)
			(layer "F.SilkS")
			(hide yes)
			(effects
				(font
					(size 1.27 1.27)
				)
			)
		)
		(property "Value" ""
			(at 0 0 180)
			(layer "F.Fab")
			(effects
				(font
					(size 1.27 1.27)
				)
			)
		)
		(duplicate_pad_numbers_are_jumpers no)
		(fp_line
			(start 0.7874 0.4064)
			(end -0.7874 0.4064)
			(stroke
				(width 0.1524)
				(type default)
			)
			(layer "F.SilkS")
		)
		(fp_line
			(start 0.7874 -0.4064)
			(end 0.7874 0.4064)
			(stroke
				(width 0.1524)
				(type default)
			)
			(layer "F.SilkS")
		)
		(fp_line
			(start -0.7874 0.4064)
			(end -0.7874 -0.4064)
			(stroke
				(width 0.1524)
				(type default)
			)
			(layer "F.SilkS")
		)
		(fp_line
			(start -0.7874 -0.4064)
			(end 0.7874 -0.4064)
			(stroke
				(width 0.1524)
				(type default)
			)
			(layer "F.SilkS")
		)
		(fp_line
			(start 0.67945 0.3048)
			(end 0.120396 0.3048)
			(stroke
				(width 0.1)
				(type default)
			)
			(layer "F.Fab")
		)
		(fp_line
			(start 0.67945 -0.3048)
			(end 0.67945 0.3048)
			(stroke
				(width 0.1)
				(type default)
			)
			(layer "F.Fab")
		)
		(fp_line
			(start 0.12065 -0.2794)
			(end 0.12065 -0.3048)
			(stroke
				(width 0.1)
				(type default)
			)
			(layer "F.Fab")
		)
		(fp_line
			(start 0.12065 -0.3048)
			(end 0.67945 -0.3048)
			(stroke
				(width 0.1)
				(type default)
			)
			(layer "F.Fab")
		)
		(fp_line
			(start 0.120396 0.3048)
			(end 0.120396 0.2794)
			(stroke
				(width 0.1)
				(type default)
			)
			(layer "F.Fab")
		)
		(fp_line
			(start 0.120396 0.2794)
			(end -0.12065 0.2794)
			(stroke
				(width 0.1)
				(type default)
			)
			(layer "F.Fab")
		)
		(fp_line
			(start -0.12065 0.3048)
			(end -0.67945 0.3048)
			(stroke
				(width 0.1)
				(type default)
			)
			(layer "F.Fab")
		)
		(fp_line
			(start -0.12065 0.2794)
			(end -0.12065 0.3048)
			(stroke
				(width 0.1)
				(type default)
			)
			(layer "F.Fab")
		)
		(fp_line
			(start -0.12065 -0.2794)
			(end 0.12065 -0.2794)
			(stroke
				(width 0.1)
				(type default)
			)
			(layer "F.Fab")
		)
		(fp_line
			(start -0.12065 -0.305054)
			(end -0.12065 -0.2794)
			(stroke
				(width 0.1)
				(type default)
			)
			(layer "F.Fab")
		)
		(fp_line
			(start -0.67945 0.3048)
			(end -0.67945 -0.305054)
			(stroke
				(width 0.1)
				(type default)
			)
			(layer "F.Fab")
		)
		(fp_line
			(start -0.67945 -0.305054)
			(end -0.12065 -0.305054)
			(stroke
				(width 0.1)
				(type default)
			)
			(layer "F.Fab")
		)
		(pad "1" smd circle
			(at -0.40005 0 180)
			(size 0 0)
			(layers "F.Cu" "F.Mask" "F.Paste")
			(net "PVDD18_S5_P0")
		)
		(pad "2" smd circle
			(at 0.40005 0 180)
			(size 0 0)
			(layers "F.Cu" "F.Mask" "F.Paste")
			(net "SPI_CPU0_D1")
		)
	)
)
